# SCM (Grand Teton) — schematic netlist excerpt (pin names and nets, part order shuffled) for the footprints in the layout excerpt that follows; sources: Cadence DE-HDL packaged netlist, KiCad conversion of 12092022_DA0F0TMDCD0_F0T_Management_Board_D_brd_V3_OCP.brd

R675  Q_RES  0 5% CHIP  pkg 0402LF  page 29 : A = USB3_01_MUX_FB_RXP ; B = USB3_01_FB_RXP
R809  Q_RES  10K 1% CHIP  pkg 0402LF  page 34 : A = PU_FPGA_NCONFIG ; B = PVCCIO_AUX_PLD

(kicad_pcb
	(version 20260206)
	(generator "pcbnew")
	(generator_version "10.0")
	(general
		(thickness 1.6)
		(legacy_teardrops no)
	)
	(paper "A4")
	(title_block
		(title "12092022_DA0F0TMDCD0_F0T_Management_Board_D_brd_V3_OCP.brd")
		(comment 1 "Grand Teton / footprints 586-587 of 1440")
	)
	(layers
		(0 "F.Cu" signal "TOP")
		(4 "In1.Cu" signal "GND")
		(6 "In2.Cu" signal "IN1")
		(8 "In3.Cu" signal "GND1")
		(10 "In4.Cu" signal "IN2")
		(12 "In5.Cu" signal "VCC")
		(14 "In6.Cu" signal "VCC1")
		(16 "In7.Cu" signal "IN3")
		(18 "In8.Cu" signal "GND2")
		(20 "In9.Cu" signal "IN4")
		(22 "In10.Cu" signal "GND3")
		(2 "B.Cu" signal "BOTTOM")
		(9 "F.Adhes" user "F.Adhesive")
		(11 "B.Adhes" user "B.Adhesive")
		(13 "F.Paste" user "Package Geometry/Pastemask Top")
		(15 "B.Paste" user "Package Geometry/Pastemask Bottom")
		(5 "F.SilkS" user "Ref Des/Silkscreen Top")
		(7 "B.SilkS" user "Ref Des/Silkscreen Bottom")
		(1 "F.Mask" user "Board Geometry/Soldermask Top")
		(3 "B.Mask" user "Board Geometry/Soldermask Bottom")
		(17 "Dwgs.User" user "User.Drawings")
		(19 "Cmts.User" user "User.Comments")
		(21 "Eco1.User" user "User.Eco1")
		(23 "Eco2.User" user "User.Eco2")
		(25 "Edge.Cuts" user "Board Geometry/Outline")
		(27 "Margin" user)
		(31 "F.CrtYd" user "Package Geometry/Place Bound Top")
		(29 "B.CrtYd" user "Package Geometry/Place Bound Bottom")
		(35 "F.Fab" user "Ref Des/Assembly Top")
		(33 "B.Fab" user "Ref Des/Assembly Bottom")
	)
	(footprint ""
		(layer "F.Cu")
		(at 30.5562 -88.9762)
		(property "Reference" "R809"
			(at 0 0 0)
			(layer "F.SilkS")
			(hide yes)
			(effects
				(font
					(size 1.27 1.27)
				)
			)
		)
		(property "Value" ""
			(at 0 0 0)
			(layer "F.Fab")
			(effects
				(font
					(size 1.27 1.27)
				)
			)
		)
		(duplicate_pad_numbers_are_jumpers no)
		(fp_line
			(start -0.7874 -0.4064)
			(end 0.7874 -0.4064)
			(stroke
				(width 0.1524)
				(type default)
			)
			(layer "F.SilkS")
		)
		(fp_line
			(start -0.7874 0.4064)
			(end -0.7874 -0.4064)
			(stroke
				(width 0.1524)
				(type default)
			)
			(layer "F.SilkS")
		)
		(fp_line
			(start 0.7874 -0.4064)
			(end 0.7874 0.4064)
			(stroke
				(width 0.1524)
				(type default)
			)
			(layer "F.SilkS")
		)
		(fp_line
			(start 0.7874 0.4064)
			(end -0.7874 0.4064)
			(stroke
				(width 0.1524)
				(type default)
			)
			(layer "F.SilkS")
		)
		(fp_line
			(start -0.67945 -0.305054)
			(end -0.12065 -0.305054)
			(stroke
				(width 0.1)
				(type default)
			)
			(layer "F.Fab")
		)
		(fp_line
			(start -0.67945 0.3048)
			(end -0.67945 -0.305054)
			(stroke
				(width 0.1)
				(type default)
			)
			(layer "F.Fab")
		)
		(fp_line
			(start -0.12065 -0.305054)
			(end -0.12065 -0.2794)
			(stroke
				(width 0.1)
				(type default)
			)
			(layer "F.Fab")
		)
		(fp_line
			(start -0.12065 -0.2794)
			(end 0.12065 -0.2794)
			(stroke
				(width 0.1)
				(type default)
			)
			(layer "F.Fab")
		)
		(fp_line
			(start -0.12065 0.2794)
			(end -0.12065 0.3048)
			(stroke
				(width 0.1)
				(type default)
			)
			(layer "F.Fab")
		)
		(fp_line
			(start -0.12065 0.3048)
			(end -0.67945 0.3048)
			(stroke
				(width 0.1)
				(type default)
			)
			(layer "F.Fab")
		)
		(fp_line
			(start 0.120396 0.2794)
			(end -0.12065 0.2794)
			(stroke
				(width 0.1)
				(type default)
			)
			(layer "F.Fab")
		)
		(fp_line
			(start 0.120396 0.3048)
			(end 0.120396 0.2794)
			(stroke
				(width 0.1)
				(type default)
			)
			(layer "F.Fab")
		)
		(fp_line
			(start 0.12065 -0.3048)
			(end 0.67945 -0.3048)
			(stroke
				(width 0.1)
				(type default)
			)
			(layer "F.Fab")
		)
		(fp_line
			(start 0.12065 -0.2794)
			(end 0.12065 -0.3048)
			(stroke
				(width 0.1)
				(type default)
			)
			(layer "F.Fab")
		)
		(fp_line
			(start 0.67945 -0.3048)
			(end 0.67945 0.3048)
			(stroke
				(width 0.1)
				(type default)
			)
			(layer "F.Fab")
		)
		(fp_line
			(start 0.67945 0.3048)
			(end 0.120396 0.3048)
			(stroke
				(width 0.1)
				(type default)
			)
			(layer "F.Fab")
		)
		(pad "1" smd circle
			(at -0.40005 0)
			(size 0 0)
			(layers "F.Cu" "F.Mask" "F.Paste")
			(net "PU_FPGA_NCONFIG")
		)
		(pad "2" smd circle
			(at 0.40005 0)
			(size 0 0)
			(layers "F.Cu" "F.Mask" "F.Paste")
			(net "PVCCIO_AUX_PLD")
		)
	)
	(footprint ""
		(layer "F.Cu")
		(at 42.950638 -22.15642 -90)
		(property "Reference" "R675"
			(at 0 0 270)
			(layer "F.SilkS")
			(hide yes)
			(effects
				(font
					(size 1.27 1.27)
				)
			)
		)
		(property "Value" ""
			(at 0 0 270)
			(layer "F.Fab")
			(effects
				(font
					(size 1.27 1.27)
				)
			)
		)
		(duplicate_pad_numbers_are_jumpers no)
		(fp_line
			(start 0.7874 0.4064)
			(end -0.7874 0.4064)
			(stroke
				(width 0.1524)
				(type default)
			)
			(layer "F.SilkS")
		)
		(fp_line
			(start -0.7874 -0.4064)
			(end 0.7874 -0.4064)
			(stroke
				(width 0.1524)
				(type default)
			)
			(layer "F.SilkS")
		)
		(fp_line
			(start -0.67945 0.3048)
			(end -0.67945 -0.305054)
			(stroke
				(width 0.1)
				(type default)
			)
			(layer "F.Fab")
		)
		(fp_line
			(start -0.12065 0.3048)
			(end -0.67945 0.3048)
			(stroke
				(width 0.1)
				(type default)
			)
			(layer "F.Fab")
		)
		(fp_line
			(start 0.120396 0.3048)
			(end 0.120396 0.2794)
			(stroke
				(width 0.1)
				(type default)
			)
			(layer "F.Fab")
		)
		(fp_line
			(start 0.67945 0.3048)
			(end 0.120396 0.3048)
			(stroke
				(width 0.1)
				(type default)
			)
			(layer "F.Fab")
		)
		(fp_line
			(start -0.12065 0.2794)
			(end -0.12065 0.3048)
			(stroke
				(width 0.1)
				(type default)
			)
			(layer "F.Fab")
		)
		(fp_line
			(start 0.120396 0.2794)
			(end -0.12065 0.2794)
			(stroke
				(width 0.1)
				(type default)
			)
			(layer "F.Fab")
		)
		(fp_line
			(start -0.12065 -0.2794)
			(end 0.12065 -0.2794)
			(stroke
				(width 0.1)
				(type default)
			)
			(layer "F.Fab")
		)
		(fp_line
			(start 0.12065 -0.2794)
			(end 0.12065 -0.3048)
			(stroke
				(width 0.1)
				(type default)
			)
			(layer "F.Fab")
		)
		(fp_line
			(start 0.12065 -0.3048)
			(end 0.67945 -0.3048)
			(stroke
				(width 0.1)
				(type default)
			)
			(layer "F.Fab")
		)
		(fp_line
			(start 0.67945 -0.3048)
			(end 0.67945 0.3048)
			(stroke
				(width 0.1)
				(type default)
			)
			(layer "F.Fab")
		)
		(fp_line
			(start -0.67945 -0.305054)
			(end -0.12065 -0.305054)
			(stroke
				(width 0.1)
				(type default)
			)
			(layer "F.Fab")
		)
		(fp_line
			(start -0.12065 -0.305054)
			(end -0.12065 -0.2794)
			(stroke
				(width 0.1)
				(type default)
			)
			(layer "F.Fab")
		)
		(pad "1" smd circle
			(at -0.40005 0 270)
			(size 0 0)
			(layers "F.Cu" "F.Mask" "F.Paste")
			(net "USB3_01_MUX_FB_RXP")
		)
		(pad "2" smd circle
			(at 0.40005 0 270)
			(size 0 0)
			(layers "F.Cu" "F.Mask" "F.Paste")
			(net "USB3_01_FB_RXP")
		)
	)
)
